(kicad_pcb
	(version 20241229)
	(generator "pcbnew")
	(generator_version "9.0")
	(general
		(thickness 1.711)
		(legacy_teardrops no)
	)
	(paper "A4")
	(title_block
		(title "Antmicro Baseboard for Jetson AGX Thor")
		(date "2026-02-18")
		(rev "1.1.0")
		(company "Antmicro Ltd")
		(comment 1 "www.antmicro.com")
		(comment 9 "footprint 710 of 1170 (J18), pads 371-462 of 564")
	)
	(layers
		(0 "F.Cu" signal)
		(4 "In1.Cu" signal)
		(6 "In2.Cu" signal)
		(8 "In3.Cu" signal)
		(10 "In4.Cu" jumper)
		(12 "In5.Cu" signal)
		(14 "In6.Cu" signal)
		(16 "In7.Cu" signal)
		(18 "In8.Cu" signal)
		(2 "B.Cu" signal)
		(9 "F.Adhes" user "F.Adhesive")
		(11 "B.Adhes" user "B.Adhesive")
		(13 "F.Paste" user)
		(15 "B.Paste" user)
		(5 "F.SilkS" user "F.Silkscreen")
		(7 "B.SilkS" user "B.Silkscreen")
		(1 "F.Mask" user)
		(3 "B.Mask" user)
		(17 "Dwgs.User" user "User.Drawings")
		(19 "Cmts.User" user "User.Comments")
		(21 "Eco1.User" user "User.Eco1")
		(23 "Eco2.User" user "User.Eco2")
		(25 "Edge.Cuts" user)
		(27 "Margin" user)
		(31 "F.CrtYd" user "F.Courtyard")
		(29 "B.CrtYd" user "B.Courtyard")
		(35 "F.Fab" user)
		(33 "B.Fab" user)
	)
	(footprint "antmicro-footprints:ASP-208571-01_mounting_holes"
		(locked yes)
		(layer "B.Cu")
		(at 77.680532 103.71 90)
		(property "Reference" "J18"
			(at -25.89 11.119468 270)
			(layer "B.SilkS")
			(effects
				(font
					(size 0.7 0.7)
					(thickness 0.15)
				)
				(justify left bottom mirror)
			)
		)
		(property "Value" "ASP-208571-01_mounting_holes"
			(at -15.05 -10.885 270)
			(layer "B.Fab")
			(effects
				(font
					(size 0.7 0.7)
					(thickness 0.15)
				)
				(justify left bottom mirror)
			)
		)
		(property "Datasheet" "https://suddendocs.samtec.com/prints/asp-208571-01-mkt.pdf"
			(at 0 0 270)
			(layer "B.Fab")
			(hide yes)
			(effects
				(font
					(size 1.27 1.27)
					(thickness 0.15)
				)
				(justify mirror)
			)
		)
		(property "Description" "FMC connector"
			(at 0 0 270)
			(layer "B.Fab")
			(hide yes)
			(effects
				(font
					(size 1.27 1.27)
					(thickness 0.15)
				)
				(justify mirror)
			)
		)
		(property "MPN" "ASP-208571-01"
			(at 0 0 90)
			(unlocked yes)
			(layer "B.Fab")
			(hide yes)
			(effects
				(font
					(size 1 1)
					(thickness 0.15)
				)
				(justify mirror)
			)
		)
		(property "Manufacturer" "Samtec"
			(at 0 0 90)
			(unlocked yes)
			(layer "B.Fab")
			(hide yes)
			(effects
				(font
					(size 1 1)
					(thickness 0.15)
				)
				(justify mirror)
			)
		)
		(property "Author" "Antmicro"
			(at 0 0 90)
			(unlocked yes)
			(layer "B.Fab")
			(hide yes)
			(effects
				(font
					(size 1 1)
					(thickness 0.15)
				)
				(justify mirror)
			)
		)
		(property "License" "Apache-2.0"
			(at 0 0 90)
			(unlocked yes)
			(layer "B.Fab")
			(hide yes)
			(effects
				(font
					(size 1 1)
					(thickness 0.15)
				)
				(justify mirror)
			)
		)
		(sheetname "/Expansion connector/")
		(sheetfile "expansion_connector.kicad_sch")
		(attr smd)
		(pad "K07" smd circle
			(at 17.145 -5.715 90)
			(size 0.64 0.64)
			(layers "B.Cu" "B.Mask")
			(net 451 "unconnected-(J18-PadK07)")
			(pinfunction "K07")
			(pintype "passive+no_connect")
		)
		(pad "K08" smd circle
			(at 15.875 -5.715 90)
			(size 0.64 0.64)
			(layers "B.Cu" "B.Mask")
			(net 387 "unconnected-(J18-PadK08)")
			(pinfunction "K08")
			(pintype "passive+no_connect")
		)
		(pad "K09" smd circle
			(at 14.605 -5.715 90)
			(size 0.64 0.64)
			(layers "B.Cu" "B.Mask")
			(net 1 "GND")
			(pinfunction "K09")
			(pintype "passive")
		)
		(pad "K10" smd circle
			(at 13.335 -5.715 90)
			(size 0.64 0.64)
			(layers "B.Cu" "B.Mask")
			(net 486 "unconnected-(J18-PadK10)")
			(pinfunction "K10")
			(pintype "passive+no_connect")
		)
		(pad "K11" smd circle
			(at 12.065 -5.715 90)
			(size 0.64 0.64)
			(layers "B.Cu" "B.Mask")
			(net 406 "unconnected-(J18-PadK11)")
			(pinfunction "K11")
			(pintype "passive+no_connect")
		)
		(pad "K12" smd circle
			(at 10.795 -5.715 90)
			(size 0.64 0.64)
			(layers "B.Cu" "B.Mask")
			(net 1 "GND")
			(pinfunction "K12")
			(pintype "passive")
		)
		(pad "K13" smd circle
			(at 9.525 -5.715 90)
			(size 0.64 0.64)
			(layers "B.Cu" "B.Mask")
			(net 355 "unconnected-(J18-PadK13)")
			(pinfunction "K13")
			(pintype "passive+no_connect")
		)
		(pad "K14" smd circle
			(at 8.255 -5.715 90)
			(size 0.64 0.64)
			(layers "B.Cu" "B.Mask")
			(net 429 "unconnected-(J18-PadK14)")
			(pinfunction "K14")
			(pintype "passive+no_connect")
		)
		(pad "K15" smd circle
			(at 6.985 -5.715 90)
			(size 0.64 0.64)
			(layers "B.Cu" "B.Mask")
			(net 1 "GND")
			(pinfunction "K15")
			(pintype "passive")
		)
		(pad "K16" smd circle
			(at 5.715 -5.715 90)
			(size 0.64 0.64)
			(layers "B.Cu" "B.Mask")
			(net 338 "unconnected-(J18-PadK16)")
			(pinfunction "K16")
			(pintype "passive+no_connect")
		)
		(pad "K17" smd circle
			(at 4.445 -5.715 90)
			(size 0.64 0.64)
			(layers "B.Cu" "B.Mask")
			(net 323 "unconnected-(J18-PadK17)")
			(pinfunction "K17")
			(pintype "passive+no_connect")
		)
		(pad "K18" smd circle
			(at 3.175 -5.715 90)
			(size 0.64 0.64)
			(layers "B.Cu" "B.Mask")
			(net 1 "GND")
			(pinfunction "K18")
			(pintype "passive")
		)
		(pad "K19" smd circle
			(at 1.905 -5.715 90)
			(size 0.64 0.64)
			(layers "B.Cu" "B.Mask")
			(net 315 "unconnected-(J18-PadK19)")
			(pinfunction "K19")
			(pintype "passive+no_connect")
		)
		(pad "K20" smd circle
			(at 0.635 -5.715 90)
			(size 0.64 0.64)
			(layers "B.Cu" "B.Mask")
			(net 463 "unconnected-(J18-PadK20)")
			(pinfunction "K20")
			(pintype "passive+no_connect")
		)
		(pad "K21" smd circle
			(at -0.635 -5.715 90)
			(size 0.64 0.64)
			(layers "B.Cu" "B.Mask")
			(net 1 "GND")
			(pinfunction "K21")
			(pintype "passive")
		)
		(pad "K22" smd circle
			(at -1.905 -5.715 90)
			(size 0.64 0.64)
			(layers "B.Cu" "B.Mask")
			(net 291 "unconnected-(J18-PadK22)")
			(pinfunction "K22")
			(pintype "passive+no_connect")
		)
		(pad "K23" smd circle
			(at -3.175 -5.715 90)
			(size 0.64 0.64)
			(layers "B.Cu" "B.Mask")
			(net 286 "unconnected-(J18-PadK23)")
			(pinfunction "K23")
			(pintype "passive+no_connect")
		)
		(pad "K24" smd circle
			(at -4.445 -5.715 90)
			(size 0.64 0.64)
			(layers "B.Cu" "B.Mask")
			(net 1 "GND")
			(pinfunction "K24")
			(pintype "passive")
		)
		(pad "K25" smd circle
			(at -5.715 -5.715 90)
			(size 0.64 0.64)
			(layers "B.Cu" "B.Mask")
			(net 394 "unconnected-(J18-PadK25)")
			(pinfunction "K25")
			(pintype "passive+no_connect")
		)
		(pad "K26" smd circle
			(at -6.985 -5.715 90)
			(size 0.64 0.64)
			(layers "B.Cu" "B.Mask")
			(net 442 "unconnected-(J18-PadK26)")
			(pinfunction "K26")
			(pintype "passive+no_connect")
		)
		(pad "K27" smd circle
			(at -8.255 -5.715 90)
			(size 0.64 0.64)
			(layers "B.Cu" "B.Mask")
			(net 1 "GND")
			(pinfunction "K27")
			(pintype "passive")
		)
		(pad "K28" smd circle
			(at -9.525 -5.715 90)
			(size 0.64 0.64)
			(layers "B.Cu" "B.Mask")
			(net 301 "unconnected-(J18-PadK28)")
			(pinfunction "K28")
			(pintype "passive+no_connect")
		)
		(pad "K29" smd circle
			(at -10.795 -5.715 90)
			(size 0.64 0.64)
			(layers "B.Cu" "B.Mask")
			(net 369 "unconnected-(J18-PadK29)")
			(pinfunction "K29")
			(pintype "passive+no_connect")
		)
		(pad "K30" smd circle
			(at -12.065 -5.715 90)
			(size 0.64 0.64)
			(layers "B.Cu" "B.Mask")
			(net 1 "GND")
			(pinfunction "K30")
			(pintype "passive")
		)
		(pad "K31" smd circle
			(at -13.335 -5.715 90)
			(size 0.64 0.64)
			(layers "B.Cu" "B.Mask")
			(net 335 "unconnected-(J18-PadK31)")
			(pinfunction "K31")
			(pintype "passive+no_connect")
		)
		(pad "K32" smd circle
			(at -14.605 -5.715 90)
			(size 0.64 0.64)
			(layers "B.Cu" "B.Mask")
			(net 430 "unconnected-(J18-PadK32)")
			(pinfunction "K32")
			(pintype "passive+no_connect")
		)
		(pad "K33" smd circle
			(at -15.875 -5.715 90)
			(size 0.64 0.64)
			(layers "B.Cu" "B.Mask")
			(net 1 "GND")
			(pinfunction "K33")
			(pintype "passive")
		)
		(pad "K34" smd circle
			(at -17.145 -5.715 90)
			(size 0.64 0.64)
			(layers "B.Cu" "B.Mask")
			(net 373 "unconnected-(J18-PadK34)")
			(pinfunction "K34")
			(pintype "passive+no_connect")
		)
		(pad "K35" smd circle
			(at -18.415 -5.715 90)
			(size 0.64 0.64)
			(layers "B.Cu" "B.Mask")
			(net 306 "unconnected-(J18-PadK35)")
			(pinfunction "K35")
			(pintype "passive+no_connect")
		)
		(pad "K36" smd circle
			(at -19.685 -5.715 90)
			(size 0.64 0.64)
			(layers "B.Cu" "B.Mask")
			(net 1 "GND")
			(pinfunction "K36")
			(pintype "passive")
		)
		(pad "K37" smd circle
			(at -20.955 -5.715 90)
			(size 0.64 0.64)
			(layers "B.Cu" "B.Mask")
			(net 336 "unconnected-(J18-PadK37)")
			(pinfunction "K37")
			(pintype "passive+no_connect")
		)
		(pad "K38" smd circle
			(at -22.225 -5.715 90)
			(size 0.64 0.64)
			(layers "B.Cu" "B.Mask")
			(net 328 "unconnected-(J18-PadK38)")
			(pinfunction "K38")
			(pintype "passive+no_connect")
		)
		(pad "K39" smd circle
			(at -23.495 -5.715 90)
			(size 0.64 0.64)
			(layers "B.Cu" "B.Mask")
			(net 1 "GND")
			(pinfunction "K39")
			(pintype "passive")
		)
		(pad "K40" smd circle
			(at -24.765 -5.715 90)
			(size 0.64 0.64)
			(layers "B.Cu" "B.Mask")
			(net 360 "Net-(J18-PadK40)")
			(pinfunction "K40")
			(pintype "passive")
		)
		(pad "L01" smd circle
			(at 24.765 -6.985 90)
			(size 0.64 0.64)
			(layers "B.Cu" "B.Mask")
			(net 717 "Net-(J18-PadL01)")
			(pinfunction "L01")
			(pintype "passive")
		)
		(pad "L02" smd circle
			(at 23.495 -6.985 90)
			(size 0.64 0.64)
			(layers "B.Cu" "B.Mask")
			(net 1 "GND")
			(pinfunction "L02")
			(pintype "passive")
		)
		(pad "L03" smd circle
			(at 22.225 -6.985 90)
			(size 0.64 0.64)
			(layers "B.Cu" "B.Mask")
			(net 1 "GND")
			(pinfunction "L03")
			(pintype "passive")
		)
		(pad "L04" smd circle
			(at 20.955 -6.985 90)
			(size 0.64 0.64)
			(layers "B.Cu" "B.Mask")
			(net 462 "unconnected-(J18-PadL04)")
			(pinfunction "L04")
			(pintype "passive+no_connect")
		)
		(pad "L05" smd circle
			(at 19.685 -6.985 90)
			(size 0.64 0.64)
			(layers "B.Cu" "B.Mask")
			(net 419 "unconnected-(J18-PadL05)")
			(pinfunction "L05")
			(pintype "passive+no_connect")
		)
		(pad "L06" smd circle
			(at 18.415 -6.985 90)
			(size 0.64 0.64)
			(layers "B.Cu" "B.Mask")
			(net 1 "GND")
			(pinfunction "L06")
			(pintype "passive")
		)
		(pad "L07" smd circle
			(at 17.145 -6.985 90)
			(size 0.64 0.64)
			(layers "B.Cu" "B.Mask")
			(net 1 "GND")
			(pinfunction "L07")
			(pintype "passive")
		)
		(pad "L08" smd circle
			(at 15.875 -6.985 90)
			(size 0.64 0.64)
			(layers "B.Cu" "B.Mask")
			(net 1361 "unconnected-(J18-PadL08)")
			(pinfunction "L08")
			(pintype "passive+no_connect")
		)
		(pad "L09" smd circle
			(at 14.605 -6.985 90)
			(size 0.64 0.64)
			(layers "B.Cu" "B.Mask")
			(net 1343 "unconnected-(J18-PadL09)")
			(pinfunction "L09")
			(pintype "passive+no_connect")
		)
		(pad "L10" smd circle
			(at 13.335 -6.985 90)
			(size 0.64 0.64)
			(layers "B.Cu" "B.Mask")
			(net 1 "GND")
			(pinfunction "L10")
			(pintype "passive")
		)
		(pad "L11" smd circle
			(at 12.065 -6.985 90)
			(size 0.64 0.64)
			(layers "B.Cu" "B.Mask")
			(net 1 "GND")
			(pinfunction "L11")
			(pintype "passive")
		)
		(pad "L12" smd circle
			(at 10.795 -6.985 90)
			(size 0.64 0.64)
			(layers "B.Cu" "B.Mask")
			(net 1356 "unconnected-(J18-PadL12)")
			(pinfunction "L12")
			(pintype "passive+no_connect")
		)
		(pad "L13" smd circle
			(at 9.525 -6.985 90)
			(size 0.64 0.64)
			(layers "B.Cu" "B.Mask")
			(net 1342 "unconnected-(J18-PadL13)")
			(pinfunction "L13")
			(pintype "passive+no_connect")
		)
		(pad "L14" smd circle
			(at 8.255 -6.985 90)
			(size 0.64 0.64)
			(layers "B.Cu" "B.Mask")
			(net 1 "GND")
			(pinfunction "L14")
			(pintype "passive")
		)
		(pad "L15" smd circle
			(at 6.985 -6.985 90)
			(size 0.64 0.64)
			(layers "B.Cu" "B.Mask")
			(net 1 "GND")
			(pinfunction "L15")
			(pintype "passive")
		)
		(pad "L16" smd circle
			(at 5.715 -6.985 90)
			(size 0.64 0.64)
			(layers "B.Cu" "B.Mask")
			(net 389 "unconnected-(J18-PadL16)")
			(pinfunction "L16")
			(pintype "passive+no_connect")
		)
		(pad "L17" smd circle
			(at 4.445 -6.985 90)
			(size 0.64 0.64)
			(layers "B.Cu" "B.Mask")
			(net 433 "unconnected-(J18-PadL17)")
			(pinfunction "L17")
			(pintype "passive+no_connect")
		)
		(pad "L18" smd circle
			(at 3.175 -6.985 90)
			(size 0.64 0.64)
			(layers "B.Cu" "B.Mask")
			(net 1 "GND")
			(pinfunction "L18")
			(pintype "passive")
		)
		(pad "L19" smd circle
			(at 1.905 -6.985 90)
			(size 0.64 0.64)
			(layers "B.Cu" "B.Mask")
			(net 1 "GND")
			(pinfunction "L19")
			(pintype "passive")
		)
		(pad "L20" smd circle
			(at 0.635 -6.985 90)
			(size 0.64 0.64)
			(layers "B.Cu" "B.Mask")
			(net 327 "unconnected-(J18-PadL20)")
			(pinfunction "L20")
			(pintype "passive+no_connect")
		)
		(pad "L21" smd circle
			(at -0.635 -6.985 90)
			(size 0.64 0.64)
			(layers "B.Cu" "B.Mask")
			(net 303 "unconnected-(J18-PadL21)")
			(pinfunction "L21")
			(pintype "passive+no_connect")
		)
		(pad "L22" smd circle
			(at -1.905 -6.985 90)
			(size 0.64 0.64)
			(layers "B.Cu" "B.Mask")
			(net 1 "GND")
			(pinfunction "L22")
			(pintype "passive")
		)
		(pad "L23" smd circle
			(at -3.175 -6.985 90)
			(size 0.64 0.64)
			(layers "B.Cu" "B.Mask")
			(net 1 "GND")
			(pinfunction "L23")
			(pintype "passive")
		)
		(pad "L24" smd circle
			(at -4.445 -6.985 90)
			(size 0.64 0.64)
			(layers "B.Cu" "B.Mask")
			(net 1351 "unconnected-(J18-PadL24)")
			(pinfunction "L24")
			(pintype "passive+no_connect")
		)
		(pad "L25" smd circle
			(at -5.715 -6.985 90)
			(size 0.64 0.64)
			(layers "B.Cu" "B.Mask")
			(net 1346 "unconnected-(J18-PadL25)")
			(pinfunction "L25")
			(pintype "passive+no_connect")
		)
		(pad "L26" smd circle
			(at -6.985 -6.985 90)
			(size 0.64 0.64)
			(layers "B.Cu" "B.Mask")
			(net 1 "GND")
			(pinfunction "L26")
			(pintype "passive")
		)
		(pad "L27" smd circle
			(at -8.255 -6.985 90)
			(size 0.64 0.64)
			(layers "B.Cu" "B.Mask")
			(net 1 "GND")
			(pinfunction "L27")
			(pintype "passive")
		)
		(pad "L28" smd circle
			(at -9.525 -6.985 90)
			(size 0.64 0.64)
			(layers "B.Cu" "B.Mask")
			(net 1344 "unconnected-(J18-PadL28)")
			(pinfunction "L28")
			(pintype "passive+no_connect")
		)
		(pad "L29" smd circle
			(at -10.795 -6.985 90)
			(size 0.64 0.64)
			(layers "B.Cu" "B.Mask")
			(net 1352 "unconnected-(J18-PadL29)")
			(pinfunction "L29")
			(pintype "passive+no_connect")
		)
		(pad "L30" smd circle
			(at -12.065 -6.985 90)
			(size 0.64 0.64)
			(layers "B.Cu" "B.Mask")
			(net 1 "GND")
			(pinfunction "L30")
			(pintype "passive")
		)
		(pad "L31" smd circle
			(at -13.335 -6.985 90)
			(size 0.64 0.64)
			(layers "B.Cu" "B.Mask")
			(net 1 "GND")
			(pinfunction "L31")
			(pintype "passive")
		)
		(pad "L32" smd circle
			(at -14.605 -6.985 90)
			(size 0.64 0.64)
			(layers "B.Cu" "B.Mask")
			(net 571 "Net-(J18-PadL32)")
			(pinfunction "L32")
			(pintype "passive")
		)
		(pad "L33" smd circle
			(at -15.875 -6.985 90)
			(size 0.64 0.64)
			(layers "B.Cu" "B.Mask")
			(net 709 "Net-(J18-PadL33)")
			(pinfunction "L33")
			(pintype "passive")
		)
		(pad "L34" smd circle
			(at -17.145 -6.985 90)
			(size 0.64 0.64)
			(layers "B.Cu" "B.Mask")
			(net 1 "GND")
			(pinfunction "L34")
			(pintype "passive")
		)
		(pad "L35" smd circle
			(at -18.415 -6.985 90)
			(size 0.64 0.64)
			(layers "B.Cu" "B.Mask")
			(net 1 "GND")
			(pinfunction "L35")
			(pintype "passive")
		)
		(pad "L36" smd circle
			(at -19.685 -6.985 90)
			(size 0.64 0.64)
			(layers "B.Cu" "B.Mask")
			(net 289 "/Expansion connector/+12V_FMC")
			(pinfunction "L36")
			(pintype "passive")
		)
		(pad "L37" smd circle
			(at -20.955 -6.985 90)
			(size 0.64 0.64)
			(layers "B.Cu" "B.Mask")
			(net 289 "/Expansion connector/+12V_FMC")
			(pinfunction "L37")
			(pintype "passive")
		)
		(pad "L38" smd circle
			(at -22.225 -6.985 90)
			(size 0.64 0.64)
			(layers "B.Cu" "B.Mask")
			(net 1 "GND")
			(pinfunction "L38")
			(pintype "passive")
		)
		(pad "L39" smd circle
			(at -23.495 -6.985 90)
			(size 0.64 0.64)
			(layers "B.Cu" "B.Mask")
			(net 1 "GND")
			(pinfunction "L39")
			(pintype "passive")
		)
		(pad "L40" smd circle
			(at -24.765 -6.985 90)
			(size 0.64 0.64)
			(layers "B.Cu" "B.Mask")
			(net 289 "/Expansion connector/+12V_FMC")
			(pinfunction "L40")
			(pintype "passive")
		)
		(pad "M01" smd circle
			(at 24.765 -8.255 90)
			(size 0.64 0.64)
			(layers "B.Cu" "B.Mask")
			(net 1 "GND")
			(pinfunction "M01")
			(pintype "passive")
		)
		(pad "M02" smd circle
			(at 23.495 -8.255 90)
			(size 0.64 0.64)
			(layers "B.Cu" "B.Mask")
			(net 453 "unconnected-(J18-PadM02)")
			(pinfunction "M02")
			(pintype "passive+no_connect")
		)
		(pad "M03" smd circle
			(at 22.225 -8.255 90)
			(size 0.64 0.64)
			(layers "B.Cu" "B.Mask")
			(net 485 "unconnected-(J18-PadM03)")
			(pinfunction "M03")
			(pintype "passive+no_connect")
		)
		(pad "M04" smd circle
			(at 20.955 -8.255 90)
			(size 0.64 0.64)
			(layers "B.Cu" "B.Mask")
			(net 1 "GND")
			(pinfunction "M04")
			(pintype "passive")
		)
		(pad "M05" smd circle
			(at 19.685 -8.255 90)
			(size 0.64 0.64)
			(layers "B.Cu" "B.Mask")
			(net 1 "GND")
			(pinfunction "M05")
			(pintype "passive")
		)
		(pad "M06" smd circle
			(at 18.415 -8.255 90)
			(size 0.64 0.64)
			(layers "B.Cu" "B.Mask")
			(net 348 "unconnected-(J18-PadM06)")
			(pinfunction "M06")
			(pintype "passive+no_connect")
		)
		(pad "M07" smd circle
			(at 17.145 -8.255 90)
			(size 0.64 0.64)
			(layers "B.Cu" "B.Mask")
			(net 414 "unconnected-(J18-PadM07)")
			(pinfunction "M07")
			(pintype "passive+no_connect")
		)
		(pad "M08" smd circle
			(at 15.875 -8.255 90)
			(size 0.64 0.64)
			(layers "B.Cu" "B.Mask")
			(net 1 "GND")
			(pinfunction "M08")
			(pintype "passive")
		)
		(pad "M09" smd circle
			(at 14.605 -8.255 90)
			(size 0.64 0.64)
			(layers "B.Cu" "B.Mask")
			(net 1 "GND")
			(pinfunction "M09")
			(pintype "passive")
		)
		(pad "M10" smd circle
			(at 13.335 -8.255 90)
			(size 0.64 0.64)
			(layers "B.Cu" "B.Mask")
			(net 1341 "unconnected-(J18-PadM10)")
			(pinfunction "M10")
			(pintype "passive+no_connect")
		)
		(pad "M11" smd circle
			(at 12.065 -8.255 90)
			(size 0.64 0.64)
			(layers "B.Cu" "B.Mask")
			(net 1362 "unconnected-(J18-PadM11)")
			(pinfunction "M11")
			(pintype "passive+no_connect")
		)
		(pad "M12" smd circle
			(at 10.795 -8.255 90)
			(size 0.64 0.64)
			(layers "B.Cu" "B.Mask")
			(net 1 "GND")
			(pinfunction "M12")
			(pintype "passive")
		)
		(pad "M13" smd circle
			(at 9.525 -8.255 90)
			(size 0.64 0.64)
			(layers "B.Cu" "B.Mask")
			(net 1 "GND")
			(pinfunction "M13")
			(pintype "passive")
		)
		(pad "M14" smd circle
			(at 8.255 -8.255 90)
			(size 0.64 0.64)
			(layers "B.Cu" "B.Mask")
			(net 1359 "unconnected-(J18-PadM14)")
			(pinfunction "M14")
			(pintype "passive+no_connect")
		)
		(pad "M15" smd circle
			(at 6.985 -8.255 90)
			(size 0.64 0.64)
			(layers "B.Cu" "B.Mask")
			(net 1350 "unconnected-(J18-PadM15)")
			(pinfunction "M15")
			(pintype "passive+no_connect")
		)
		(pad "M16" smd circle
			(at 5.715 -8.255 90)
			(size 0.64 0.64)
			(layers "B.Cu" "B.Mask")
			(net 1 "GND")
			(pinfunction "M16")
			(pintype "passive")
		)
		(pad "M17" smd circle
			(at 4.445 -8.255 90)
			(size 0.64 0.64)
			(layers "B.Cu" "B.Mask")
			(net 1 "GND")
			(pinfunction "M17")
			(pintype "passive")
		)
		(pad "M18" smd circle
			(at 3.175 -8.255 90)
			(size 0.64 0.64)
			(layers "B.Cu" "B.Mask")
			(net 1345 "unconnected-(J18-PadM18)")
			(pinfunction "M18")
			(pintype "passive+no_connect")
		)
	)
)
